# Lightning  PDPB_Stackup.xlsx — 工作表2 (pcb-stackup)
|  |  |  |  |  |  | Version |  |  |  |  |  |  |  |  |  |  |  |  |  |  |  |  |  |  |  |  |
| Board Number: |  | 15669-1 |  |  |  | 02 |  |  |  |  |  |  |  |  |  |  |  |  |  |  |  |  |  |  |  |  |
| Project name: |  | Lightning_PMC |  |  |  |  |  |  |  |  |  |  |  |  |  |  |  |  |  |  |  |  |  |  |  |  |
| Model Name: |  | PDPB |  |  |  |  |  |  |  |  |  |  |  |  |  |  |  |  |  |  |  |  |  |  |  |  |
| Layer Count: |  | 8 Layer |  |  |  |  |  |  |  |  |  |  |  |  |  |  |  |  |  |  |  |  |  |  |  |  |
| Date: |  | 42662 |  |  |  |  |  |  |  |  |  |  |  |  |  |  |  |  |  |  |  |  |  |  |  |  |
| Material: |  | TU863+VLP / NPG171+VLP |  |  |  |  |  |  |  | Single Ended Type(mil) |  |  |  |  | Differential Type(mil) |  |  |  |  |  |  |  |  |  |  |  |
| Gold Finger(Y/N) |  | N |  |  |  |  |  |  | Imp | 50 |  |  |  | Imp | 85 |  |  |  |  |  | 100 |  |  |  |  |  |
| Customer: |  | XXXXX |  |  |  |  |  |  | Variation | Inner/Outer+/-5ohm |  |  |  | Variation | Inner/Outer+/-10% |  |  |  |  |  | Inner/Outer+/-10% |  |  |  |  |  |
| EE engineer |  | <name> |  |  |  |  |  |  | Bus | MISC./I2C |  |  |  | Bus | PCIe/Clock |  |  |  |  |  | Clock |  |  |  |  |  |
| SI Engineer |  | <name> |  |  |  |  |  |  |  |  |  |  |  |  |  |  |  |  |  |  |  |  |  |  |  |  |
|  |  |  |  |  |  |  |  |  | Type | SE |  |  |  | Type | DP |  |  |  |  |  | DP |  |  |  |  |  |
| Layer |  |  | Thickness |  | Glass/Copper Style | Er |  | Df(1G) | Layers | 1,3,6,8 |  |  |  | Layers | 1,3,6,8 |  |  |  |  |  | 1,3,6,8 |  |  |  |  |  |
|  |  | Cu oz | Wiwynn |  |  | Wiwynn |  |  |  | Wiwynn |  |  |  |  | Wiwynn |  |  |  |  |  | Wiwynn |  |  |  |  |  |
|  | Mask |  | 0.5 |  |  | 3.4 |  | 2.5000000000000001E-2 |  | Width | Imp | Width | Imp |  | Width | Space | Imp | Width | Space | Imp | Width | Space | Imp | Width | Space | Imp |
| Top | Signal | 0.5 oz+plating | 2.1 |  |  |  |  |  | S1 | 6.75(L2) | 50.7 |  |  | S1 | 6.88(L2) | 5.13 | 84.07 |  |  |  | 5(L2) | 6 | 99.3 |  |  |  |
|  | Prepreg |  | 4 |  |  | 3.8 |  | 8.9999999999999993E-3 |  |  |  |  |  |  |  |  |  |  |  |  |  |  |  |  |  |  |
| L2 | GND | 1 oz | 1.3 |  |  |  |  |  | P2 | reference layer |  |  |  | P2 | reference layer |  |  |  |  |  | reference layer |  |  |  |  |  |
|  | Core |  | 5 |  |  | 3.8 |  | 8.9999999999999993E-3 |  |  |  |  |  |  |  |  |  |  |  |  |  |  |  |  |  |  |
| L3 | Signal | 1 oz | 1.3 |  |  |  |  |  | S3 | 6(L2/L4) | 50.47 |  |  | S3 | 6.5(L2/L4) | 7.5 | 84.49 |  |  |  | 4.5(L2/L4) | 9 | 100.81 |  |  |  |
|  | Prepreg |  | 20 |  |  | 4.5 |  | 8.9999999999999993E-3 |  |  |  |  |  |  |  |  |  |  |  |  |  |  |  |  |  |  |
| L4 | POWER | 2 oz | 2.6 |  |  |  |  |  | P4 | reference layer |  |  |  | P4 | reference layer |  |  |  |  |  | reference layer |  |  |  |  |  |
|  | Core |  | 11.4 |  |  | 4.2 | 0 | 8.9999999999999993E-3 |  |  |  |  |  |  |  |  |  |  |  |  |  |  |  |  |  |  |
| L5 | POWER | 2 oz | 2.6 | 0 | 0 |  |  |  | P5 | reference layer |  |  |  | P5 | reference layer |  |  |  |  |  | reference layer |  |  |  |  |  |
|  | Prepreg |  | 20 | 0 | 0 | 4.5 | 0 | 8.9999999999999993E-3 |  |  |  |  |  |  |  |  |  |  |  |  |  |  |  |  |  |  |
| L6 | Signal | 1 oz | 1.3 | 0 | 0 |  |  |  | S6 | 6(L5/L7) | 50.47 |  |  | S6 | 6.5(L5/L7) | 7.5 | 84.49 |  |  |  | 4.5(L5/L7) | 9 | 100.81 |  |  |  |
|  | Core |  | 5 | 0 | 0 | 3.8 | 0 | 8.9999999999999993E-3 |  |  |  |  |  |  |  |  |  |  |  |  |  |  |  |  |  |  |
| L7 | GND | 1 oz | 1.3 | 0 | 0 |  |  |  | P7 | reference layer |  |  |  | P7 | reference layer |  |  |  |  |  | reference layer |  |  |  |  |  |
|  | Prepreg |  | 4 | 0 | 0 | 3.8 | 0 | 8.9999999999999993E-3 |  |  |  |  |  |  |  |  |  |  |  |  |  |  |  |  |  |  |
| Bottom | Signal | 0.5 oz+plating | 2.1 | 0 | 0 |  |  |  | S8 | 6.75(L7) | 50.7 |  |  | S8 | 6.88(L7) | 5.13 | 84.07 |  |  |  | 5(L7) | 6 | 99.3 |  |  |  |
|  | Mask |  | 0.5 | 0 |  | 3.4 | 0 | 2.5000000000000001E-2 |  |  |  |  |  |  |  |  |  |  |  |  |  |  |  |  |  |  |
| Thickness requirement: 2.16 ± 0.1 mm |  | mil | 85 |  |  |  |  |  |  |  |  |  |  |  |  |  |  |  |  |  |  |  |  |  |  |  |
|  |  | mm | 2.1590043180086362 |  |  |  |  |  |  |  |  |  |  |  |  |  |  |  |  |  |  |  |  |  |  |  |
| Note: | 1. Unit is mil |  |  |  |  |  |  |  |  |  |  |  |  |  |  |  |  |  |  |  |  |  |  |  |  |  |
|  | 2. The total thickness includes trace and solder mask |  |  |  |  |  |  |  |  |  |  |  |  |  |  |  |  |  |  |  |  |  |  |  |  |  |
|  | 3. Min hole copper thickness is 1.0 mil |  |  |  |  |  |  |  |  |  |  |  |  |  |  |  |  |  |  |  |  |  |  |  |  |  |
|  | 4. Min surface copper thickness 1.5 mil |  |  |  |  |  |  |  |  |  |  |  |  |  |  |  |  |  |  |  |  |  |  |  |  |  |
|  | 5. Impedance Cpk requirement: >=1.33 (Report should be provided) |  |  |  |  |  |  |  |  |  |  |  |  |  |  |  |  |  |  |  |  |  |  |  |  |  |
|  | 6. PCB supplier should design Delta-L coupon and provide measurement results meeting following criteria: |  |  |  |  |  |  |  |  |  |  |  |  |  |  |  |  |  |  |  |  |  |  |  |  |  |
|  | 。  -0.65dB/inch at 4GHz for stripline routing |  |  |  |  |  |  |  |  |  |  |  |  |  |  |  |  |  |  |  |  |  |  |  |  |  |
|  | 。  -0.69dB/inch at 4GHz for microstrip routing |  |  |  |  |  |  |  |  |  |  |  |  |  |  |  |  |  |  |  |  |  |  |  |  |  |
